(kicad_pcb
	(version 20241229)
	(generator "pcbnew")
	(generator_version "9.0")
	(general
		(thickness 1.711)
		(legacy_teardrops no)
	)
	(paper "A4")
	(title_block
		(title "Antmicro Baseboard for Jetson AGX Thor")
		(date "2026-02-18")
		(rev "1.1.0")
		(company "Antmicro Ltd")
		(comment 1 "www.antmicro.com")
		(comment 9 "footprints 275-278 of 1170")
	)
	(layers
		(0 "F.Cu" signal)
		(4 "In1.Cu" signal)
		(6 "In2.Cu" signal)
		(8 "In3.Cu" signal)
		(10 "In4.Cu" jumper)
		(12 "In5.Cu" signal)
		(14 "In6.Cu" signal)
		(16 "In7.Cu" signal)
		(18 "In8.Cu" signal)
		(2 "B.Cu" signal)
		(9 "F.Adhes" user "F.Adhesive")
		(11 "B.Adhes" user "B.Adhesive")
		(13 "F.Paste" user)
		(15 "B.Paste" user)
		(5 "F.SilkS" user "F.Silkscreen")
		(7 "B.SilkS" user "B.Silkscreen")
		(1 "F.Mask" user)
		(3 "B.Mask" user)
		(17 "Dwgs.User" user "User.Drawings")
		(19 "Cmts.User" user "User.Comments")
		(21 "Eco1.User" user "User.Eco1")
		(23 "Eco2.User" user "User.Eco2")
		(25 "Edge.Cuts" user)
		(27 "Margin" user)
		(31 "F.CrtYd" user "F.Courtyard")
		(29 "B.CrtYd" user "B.Courtyard")
		(35 "F.Fab" user)
		(33 "B.Fab" user)
	)
	(footprint "antmicro-footprints:Vishay_PowerPAK_1212-8_Single"
		(layer "F.Cu")
		(at 211.214 72.51 180)
		(descr "PowerPAK 1212-8 Single")
		(tags "Vishay PowerPAK 1212-8 Single")
		(property "Reference" "Q41"
			(at 2.914 1.91 90)
			(layer "F.SilkS")
			(effects
				(font
					(size 0.7 0.7)
					(thickness 0.15)
				)
				(justify right top)
			)
		)
		(property "Value" "SISS05DN-T1-GE3"
			(at 0 2.7 0)
			(layer "F.Fab")
			(effects
				(font
					(size 0.7 0.7)
					(thickness 0.15)
				)
				(justify right top)
			)
		)
		(property "Datasheet" "https://www.vishay.com/docs/77029/siss05dn.pdf"
			(at 0 0 0)
			(layer "F.Fab")
			(hide yes)
			(effects
				(font
					(size 1.27 1.27)
					(thickness 0.15)
				)
			)
		)
		(property "Description" "Power MOSFET, P Channel, 30 V, 108 A, 0.0035 ohm, PowerPAK 1212, Surface Mount"
			(at 0 0 0)
			(layer "F.Fab")
			(hide yes)
			(effects
				(font
					(size 1.27 1.27)
					(thickness 0.15)
				)
			)
		)
		(property "MPN" "SISS05DN-T1-GE3"
			(at 0 0 180)
			(unlocked yes)
			(layer "F.Fab")
			(hide yes)
			(effects
				(font
					(size 1 1)
					(thickness 0.15)
				)
			)
		)
		(property "Manufacturer" "Vishay"
			(at 0 0 180)
			(unlocked yes)
			(layer "F.Fab")
			(hide yes)
			(effects
				(font
					(size 1 1)
					(thickness 0.15)
				)
			)
		)
		(property "Author" "Antmicro"
			(at 0 0 180)
			(unlocked yes)
			(layer "F.Fab")
			(hide yes)
			(effects
				(font
					(size 1 1)
					(thickness 0.15)
				)
			)
		)
		(property "License" "Apache-2.0"
			(at 0 0 180)
			(unlocked yes)
			(layer "F.Fab")
			(hide yes)
			(effects
				(font
					(size 1 1)
					(thickness 0.15)
				)
			)
		)
		(sheetname "/Power/")
		(sheetfile "power.kicad_sch")
		(attr smd)
		(fp_line
			(start 1.648 -1.651)
			(end 1.648 -1.317)
			(stroke
				(width 0.15)
				(type solid)
			)
			(layer "F.SilkS")
		)
		(fp_line
			(start 1.634 1.3)
			(end 1.634 1.634)
			(stroke
				(width 0.15)
				(type solid)
			)
			(layer "F.SilkS")
		)
		(fp_line
			(start -1.635 1.634)
			(end 1.634 1.634)
			(stroke
				(width 0.15)
				(type solid)
			)
			(layer "F.SilkS")
		)
		(fp_line
			(start -1.635 1.3)
			(end -1.635 1.634)
			(stroke
				(width 0.15)
				(type solid)
			)
			(layer "F.SilkS")
		)
		(fp_line
			(start -1.651 -1.651)
			(end 1.648 -1.651)
			(stroke
				(width 0.15)
				(type solid)
			)
			(layer "F.SilkS")
		)
		(fp_line
			(start -1.651 -1.651)
			(end -1.651 -1.317)
			(stroke
				(width 0.15)
				(type solid)
			)
			(layer "F.SilkS")
		)
		(fp_circle
			(center -1.9 -1.4)
			(end -1.85 -1.4)
			(stroke
				(width 0.15)
				(type solid)
			)
			(fill yes)
			(layer "F.SilkS")
		)
		(fp_rect
			(start -2 -1.8)
			(end 2 1.798)
			(stroke
				(width 0.05)
				(type solid)
			)
			(fill no)
			(layer "F.CrtYd")
		)
		(fp_line
			(start -1.6425 -1.4175)
			(end -1.4175 -1.6425)
			(stroke
				(width 0.15)
				(type solid)
			)
			(layer "F.Fab")
		)
		(fp_rect
			(start -1.651 -1.651)
			(end 1.648 1.648)
			(stroke
				(width 0.15)
				(type solid)
			)
			(fill no)
			(layer "F.Fab")
		)
		(fp_text user "License: Apache-2.0"
			(at -8 7.1 0)
			(layer "F.Fab")
			(effects
				(font
					(size 0.7 0.7)
					(thickness 0.15)
				)
				(justify right top)
			)
		)
		(fp_text user "${REFERENCE}"
			(at -8 4.7 0)
			(layer "F.Fab")
			(effects
				(font
					(size 0.7 0.7)
					(thickness 0.15)
				)
				(justify right top)
			)
		)
		(fp_text user "Author: Antmicro"
			(at -8 5.9 0)
			(layer "F.Fab")
			(effects
				(font
					(size 0.7 0.7)
					(thickness 0.15)
				)
				(justify right top)
			)
		)
		(pad "1" smd rect
			(at -1.436 -0.99 180)
			(size 0.99 0.405)
			(layers "F.Cu" "F.Mask" "F.Paste")
			(net 1383 "VCC_NO_OVP")
			(pinfunction "S")
			(pintype "passive")
		)
		(pad "2" smd rect
			(at -1.436 -0.332 180)
			(size 0.99 0.405)
			(layers "F.Cu" "F.Mask" "F.Paste")
			(net 1383 "VCC_NO_OVP")
			(pinfunction "S")
			(pintype "passive")
		)
		(pad "3" smd rect
			(at -1.436 0.33 180)
			(size 0.99 0.405)
			(layers "F.Cu" "F.Mask" "F.Paste")
			(net 1383 "VCC_NO_OVP")
			(pinfunction "S")
			(pintype "passive")
		)
		(pad "4" smd rect
			(at -1.436 0.988 180)
			(size 0.99 0.405)
			(layers "F.Cu" "F.Mask" "F.Paste")
			(net 1385 "Net-(Q41-G)")
			(pinfunction "G")
			(pintype "input")
		)
		(pad "5" smd custom
			(at 0.557 0 180)
			(size 1.725 2.235)
			(layers "F.Cu" "F.Mask" "F.Paste")
			(net 13 "VCC")
			(pinfunction "D")
			(pintype "passive")
			(zone_connect 2)
			(options
				(clearance outline)
				(anchor rect)
			)
			(primitives
				(gr_poly
					(pts
						(xy 0.8625 0.1275) (xy 0.8625 -0.1275) (xy 1.3725 -0.1275) (xy 1.3725 -0.5325) (xy 0.8625 -0.5325)
						(xy 0.8625 -0.7875) (xy 1.3725 -0.7875) (xy 1.3725 -1.195) (xy 0.6125 -1.195) (xy 0.6125 1.195)
						(xy 1.3725 1.195) (xy 1.3725 0.7875) (xy 0.8625 0.7875) (xy 0.8625 0.5325) (xy 1.3725 0.5325)
						(xy 1.3725 0.1275)
					)
					(width 0)
					(fill yes)
				)
			)
		)
	)
	(footprint "antmicro-footprints:LED_0603_1608Metric_G"
		(layer "F.Cu")
		(at 222.13 73.444951 180)
		(descr "LED SMD 0603 Green")
		(tags "LED SMD 0603 Green")
		(property "Reference" "D20"
			(at 0.68 -2.955049 180)
			(layer "F.SilkS")
			(effects
				(font
					(size 0.7 0.7)
					(thickness 0.15)
				)
				(justify left bottom)
			)
		)
		(property "Value" "LED_G_0603_LTST-C190GKT"
			(at -0.001 1.599 180)
			(layer "F.Fab")
			(effects
				(font
					(size 0.7 0.7)
					(thickness 0.15)
				)
				(justify left bottom)
			)
		)
		(property "Datasheet" "https://media.digikey.com/pdf/Data%20Sheets/Lite-On%20PDFs/LTST-C190GKT.pdf"
			(at 0 0 180)
			(layer "F.Fab")
			(hide yes)
			(effects
				(font
					(size 1.27 1.27)
					(thickness 0.15)
				)
			)
		)
		(property "Description" "LED, Green, SMD, 0603, 20 mA, 2.1 V, 569 nm"
			(at 0 0 180)
			(layer "F.Fab")
			(hide yes)
			(effects
				(font
					(size 1.27 1.27)
					(thickness 0.15)
				)
			)
		)
		(property "MPN" "LTST-C190GKT"
			(at 0 0 180)
			(unlocked yes)
			(layer "F.Fab")
			(hide yes)
			(effects
				(font
					(size 1 1)
					(thickness 0.15)
				)
			)
		)
		(property "Manufacturer" "Lite-On"
			(at 0 0 180)
			(unlocked yes)
			(layer "F.Fab")
			(hide yes)
			(effects
				(font
					(size 1 1)
					(thickness 0.15)
				)
			)
		)
		(property "Author" "Antmicro"
			(at 0 0 180)
			(unlocked yes)
			(layer "F.Fab")
			(hide yes)
			(effects
				(font
					(size 1 1)
					(thickness 0.15)
				)
			)
		)
		(property "License" "Apache-2.0"
			(at 0 0 180)
			(unlocked yes)
			(layer "F.Fab")
			(hide yes)
			(effects
				(font
					(size 1 1)
					(thickness 0.15)
				)
			)
		)
		(property "Color" "Green"
			(at 0 0 180)
			(unlocked yes)
			(layer "F.Fab")
			(hide yes)
			(effects
				(font
					(size 1 1)
					(thickness 0.15)
				)
			)
		)
		(sheetname "/USB Debug, PD/")
		(sheetfile "usb_debug_pd.kicad_sch")
		(attr smd)
		(fp_line
			(start 0.22 0.35)
			(end -0.22 0.35)
			(stroke
				(width 0.15)
				(type solid)
			)
			(layer "F.SilkS")
		)
		(fp_line
			(start 0.22 -0.35)
			(end -0.22 -0.35)
			(stroke
				(width 0.15)
				(type solid)
			)
			(layer "F.SilkS")
		)
		(fp_line
			(start 0.105328 0.201008)
			(end 0.105328 -0.198992)
			(stroke
				(width 0.1)
				(type solid)
			)
			(layer "F.SilkS")
		)
		(fp_line
			(start 0.105328 0.201008)
			(end -0.094672 0.001008)
			(stroke
				(width 0.1)
				(type solid)
			)
			(layer "F.SilkS")
		)
		(fp_line
			(start 0.105328 0.001008)
			(end 0.24 0.001)
			(stroke
				(width 0.1)
				(type solid)
			)
			(layer "F.SilkS")
		)
		(fp_line
			(start -0.094672 0.201008)
			(end -0.094672 -0.198992)
			(stroke
				(width 0.1)
				(type solid)
			)
			(layer "F.SilkS")
		)
		(fp_line
			(start -0.094672 0.001008)
			(end 0.105328 -0.198992)
			(stroke
				(width 0.1)
				(type solid)
			)
			(layer "F.SilkS")
		)
		(fp_line
			(start -0.094672 0.001008)
			(end -0.24 0.001008)
			(stroke
				(width 0.1)
				(type solid)
			)
			(layer "F.SilkS")
		)
		(fp_line
			(start -1.18 -0.319)
			(end -1.18 0.321)
			(stroke
				(width 0.15)
				(type solid)
			)
			(layer "F.SilkS")
		)
		(fp_rect
			(start 1.25 0.65)
			(end -1.25 -0.65)
			(stroke
				(width 0.05)
				(type solid)
			)
			(fill no)
			(layer "F.CrtYd")
		)
		(fp_line
			(start 0.599 0)
			(end 0.201 0)
			(stroke
				(width 0.15)
				(type solid)
			)
			(layer "F.Fab")
		)
		(fp_line
			(start 0.201 0.2)
			(end 0.201 0)
			(stroke
				(width 0.15)
				(type solid)
			)
			(layer "F.Fab")
		)
		(fp_line
			(start 0.201 0)
			(end 0.201 -0.202)
			(stroke
				(width 0.15)
				(type solid)
			)
			(layer "F.Fab")
		)
		(fp_line
			(start 0.201 -0.202)
			(end -0.101 0)
			(stroke
				(width 0.15)
				(type solid)
			)
			(layer "F.Fab")
		)
		(fp_line
			(start -0.101 0)
			(end 0.201 0.2)
			(stroke
				(width 0.15)
				(type solid)
			)
			(layer "F.Fab")
		)
		(fp_line
			(start -0.199 0.2)
			(end -0.199 0.1)
			(stroke
				(width 0.15)
				(type solid)
			)
			(layer "F.Fab")
		)
		(fp_line
			(start -0.199 0)
			(end -0.597 0)
			(stroke
				(width 0.15)
				(type solid)
			)
			(layer "F.Fab")
		)
		(fp_line
			(start -0.199 -0.202)
			(end -0.199 0.1)
			(stroke
				(width 0.15)
				(type solid)
			)
			(layer "F.Fab")
		)
		(fp_rect
			(start 0.848 0.4)
			(end -0.85 -0.402)
			(stroke
				(width 0.15)
				(type solid)
			)
			(fill no)
			(layer "F.Fab")
		)
		(fp_text user "${REFERENCE}"
			(at -1.4224 5.999 180)
			(layer "F.Fab")
			(effects
				(font
					(size 0.7 0.7)
					(thickness 0.15)
				)
				(justify left bottom)
			)
		)
		(fp_text user "License: Apache-2.0"
			(at -1.4224 3.599 180)
			(layer "F.Fab")
			(effects
				(font
					(size 0.7 0.7)
					(thickness 0.15)
				)
				(justify left bottom)
			)
		)
		(fp_text user "Author: Antmicro"
			(at -1.4224 4.799 180)
			(layer "F.Fab")
			(effects
				(font
					(size 0.7 0.7)
					(thickness 0.15)
				)
				(justify left bottom)
			)
		)
		(pad "1" smd roundrect
			(at -0.7 0)
			(size 0.8 1)
			(layers "F.Cu" "F.Mask" "F.Paste")
			(roundrect_rratio 0.2)
			(net 536 "/USB Debug, PD/FTDI_LED_TX")
			(pinfunction "C")
			(pintype "passive")
		)
		(pad "2" smd roundrect
			(at 0.7 0)
			(size 0.8 1)
			(layers "F.Cu" "F.Mask" "F.Paste")
			(roundrect_rratio 0.2)
			(net 535 "Net-(D20-A)")
			(pinfunction "A")
			(pintype "passive")
		)
	)
	(footprint "antmicro-footprints:SOT-523"
		(layer "F.Cu")
		(at 160.3 62.8 90)
		(property "Reference" "Q36"
			(at -2.1 -1.3 180)
			(layer "F.SilkS")
			(effects
				(font
					(size 0.7 0.7)
					(thickness 0.15)
				)
				(justify left bottom)
			)
		)
		(property "Value" "DMG1012T-7"
			(at 0.1 1.824 90)
			(layer "F.Fab")
			(effects
				(font
					(size 0.7 0.7)
					(thickness 0.15)
				)
				(justify left bottom)
			)
		)
		(property "Datasheet" "https://www.diodes.com/assets/Datasheets/ds31783.pdf"
			(at 0 0 90)
			(layer "F.Fab")
			(hide yes)
			(effects
				(font
					(size 1.27 1.27)
					(thickness 0.15)
				)
			)
		)
		(property "Description" "Power MOSFET, N Channel, 20 V, 630 mA, 0.3 ohm, SOT-523, Surface Mount"
			(at 0 0 90)
			(layer "F.Fab")
			(hide yes)
			(effects
				(font
					(size 1.27 1.27)
					(thickness 0.15)
				)
			)
		)
		(property "MPN" "DMG1012T-7"
			(at 0 0 90)
			(unlocked yes)
			(layer "F.Fab")
			(hide yes)
			(effects
				(font
					(size 1 1)
					(thickness 0.15)
				)
			)
		)
		(property "Manufacturer" "Diodes Incorporated"
			(at 0 0 90)
			(unlocked yes)
			(layer "F.Fab")
			(hide yes)
			(effects
				(font
					(size 1 1)
					(thickness 0.15)
				)
			)
		)
		(property "Author" "Antmicro"
			(at 0 0 90)
			(unlocked yes)
			(layer "F.Fab")
			(hide yes)
			(effects
				(font
					(size 1 1)
					(thickness 0.15)
				)
			)
		)
		(property "License" "Apache-2.0"
			(at 0 0 90)
			(unlocked yes)
			(layer "F.Fab")
			(hide yes)
			(effects
				(font
					(size 1 1)
					(thickness 0.15)
				)
			)
		)
		(sheetname "/SoM_IO2/")
		(sheetfile "som_io2.kicad_sch")
		(attr smd exclude_from_pos_files exclude_from_bom dnp)
		(fp_line
			(start -0.277 -0.551)
			(end -0.277 -0.750001)
			(stroke
				(width 0.15)
				(type solid)
			)
			(layer "F.SilkS")
		)
		(fp_line
			(start -0.725 -0.551)
			(end -0.277 -0.551)
			(stroke
				(width 0.15)
				(type solid)
			)
			(layer "F.SilkS")
		)
		(fp_line
			(start -0.927 -0.350999)
			(end -0.725 -0.551)
			(stroke
				(width 0.15)
				(type solid)
			)
			(layer "F.SilkS")
		)
		(fp_line
			(start -0.927 -0.050999)
			(end -0.927 -0.350999)
			(stroke
				(width 0.15)
				(type solid)
			)
			(layer "F.SilkS")
		)
		(fp_circle
			(center -0.9652 0.9652)
			(end -0.915201 0.9652)
			(stroke
				(width 0.15)
				(type solid)
			)
			(fill yes)
			(layer "F.SilkS")
		)
		(fp_line
			(start 1.1 -1.159999)
			(end 1.1 1.15)
			(stroke
				(width 0.05)
				(type solid)
			)
			(layer "F.CrtYd")
		)
		(fp_line
			(start -1.12 -1.159999)
			(end 1.1 -1.159999)
			(stroke
				(width 0.05)
				(type solid)
			)
			(layer "F.CrtYd")
		)
		(fp_line
			(start -1.12 -1.159999)
			(end -1.12 1.15)
			(stroke
				(width 0.05)
				(type solid)
			)
			(layer "F.CrtYd")
		)
		(fp_line
			(start -1.12 1.15)
			(end 1.1 1.15)
			(stroke
				(width 0.05)
				(type solid)
			)
			(layer "F.CrtYd")
		)
		(fp_line
			(start 0.8 -0.425)
			(end -0.652 -0.425)
			(stroke
				(width 0.15)
				(type solid)
			)
			(layer "F.Fab")
		)
		(fp_line
			(start 0.8 -0.425)
			(end 0.8 0.424)
			(stroke
				(width 0.15)
				(type solid)
			)
			(layer "F.Fab")
		)
		(fp_line
			(start -0.652 -0.425)
			(end -0.802 -0.276)
			(stroke
				(width 0.15)
				(type solid)
			)
			(layer "F.Fab")
		)
		(fp_line
			(start -0.802 -0.276)
			(end -0.802 0.424)
			(stroke
				(width 0.15)
				(type solid)
			)
			(layer "F.Fab")
		)
		(fp_line
			(start 0.8 0.424)
			(end -0.802 0.424)
			(stroke
				(width 0.15)
				(type solid)
			)
			(layer "F.Fab")
		)
		(fp_circle
			(center -0.9652 0.9652)
			(end -0.9144 0.9652)
			(stroke
				(width 0.15)
				(type solid)
			)
			(fill no)
			(layer "F.Fab")
		)
		(fp_text user "${REFERENCE}"
			(at -1.12 3.824 90)
			(layer "F.Fab")
			(effects
				(font
					(size 0.7 0.7)
					(thickness 0.15)
				)
				(justify left bottom)
			)
		)
		(fp_text user "License: Apache-2.0"
			(at -1.12 5.024 90)
			(layer "F.Fab")
			(effects
				(font
					(size 0.7 0.7)
					(thickness 0.15)
				)
				(justify left bottom)
			)
		)
		(fp_text user "Author: Antmicro"
			(at -1.12 6.224 90)
			(layer "F.Fab")
			(effects
				(font
					(size 0.7 0.7)
					(thickness 0.15)
				)
				(justify left bottom)
			)
		)
		(pad "1" smd rect
			(at -0.5 0.65 90)
			(size 0.4 0.51)
			(layers "F.Cu" "F.Mask" "F.Paste")
			(net 870 "/SoM_IO2/TC_JTAG_TRST_N")
			(pinfunction "G")
			(pintype "input")
		)
		(pad "2" smd rect
			(at 0.498 0.65 90)
			(size 0.4 0.51)
			(layers "F.Cu" "F.Mask" "F.Paste")
			(net 1 "GND")
			(pinfunction "S")
			(pintype "passive")
		)
		(pad "3" smd rect
			(at 0 -0.652001 90)
			(size 0.4 0.51)
			(layers "F.Cu" "F.Mask" "F.Paste")
			(net 1299 "Net-(Q28-G)")
			(pinfunction "D")
			(pintype "passive")
		)
	)
	(footprint "antmicro-footprints:R_0402_1005Metric"
		(layer "F.Cu")
		(at 132.465349 61.976557)
		(descr "Resistor SMD 0402")
		(tags "resistor SMD 0402")
		(property "Reference" "R309"
			(at 0.844651 1.333443 0)
			(layer "F.SilkS")
			(effects
				(font
					(size 0.7 0.7)
					(thickness 0.15)
				)
				(justify left bottom)
			)
		)
		(property "Value" "R_499k_0402"
			(at -1.011843 1.772046 0)
			(layer "F.Fab")
			(effects
				(font
					(size 0.7 0.7)
					(thickness 0.15)
				)
				(justify left bottom)
			)
		)
		(property "Datasheet" "https://www.mouser.com/datasheet/2/54/cr-1858361.pdf"
			(at 0 0 0)
			(layer "F.Fab")
			(hide yes)
			(effects
				(font
					(size 1.27 1.27)
					(thickness 0.15)
				)
			)
		)
		(property "Description" "SMD Chip Resistor, 499 kohm, ± 1%, 63 mW, 0402 [1005 Metric], Thick Film, General Purpose"
			(at 0 0 0)
			(layer "F.Fab")
			(hide yes)
			(effects
				(font
					(size 1.27 1.27)
					(thickness 0.15)
				)
			)
		)
		(property "MPN" "CR0402-FX-4993GLF"
			(at 0 0 0)
			(unlocked yes)
			(layer "F.Fab")
			(hide yes)
			(effects
				(font
					(size 1 1)
					(thickness 0.15)
				)
			)
		)
		(property "Manufacturer" "Bourns"
			(at 0 0 0)
			(unlocked yes)
			(layer "F.Fab")
			(hide yes)
			(effects
				(font
					(size 1 1)
					(thickness 0.15)
				)
			)
		)
		(property "License" "Apache-2.0"
			(at 0 0 0)
			(unlocked yes)
			(layer "F.Fab")
			(hide yes)
			(effects
				(font
					(size 1 1)
					(thickness 0.15)
				)
			)
		)
		(property "Author" "Antmicro"
			(at 0 0 0)
			(unlocked yes)
			(layer "F.Fab")
			(hide yes)
			(effects
				(font
					(size 1 1)
					(thickness 0.15)
				)
			)
		)
		(property "Val" "499k"
			(at 0 0 0)
			(unlocked yes)
			(layer "F.Fab")
			(hide yes)
			(effects
				(font
					(size 1 1)
					(thickness 0.15)
				)
			)
		)
		(property "Tolerance" "1%"
			(at 0 0 0)
			(unlocked yes)
			(layer "F.Fab")
			(hide yes)
			(effects
				(font
					(size 1 1)
					(thickness 0.15)
				)
			)
		)
		(sheetname "/DCDC/")
		(sheetfile "dcdc.kicad_sch")
		(attr smd exclude_from_pos_files exclude_from_bom dnp)
		(fp_poly
			(pts
				(xy -0.925 -0.47) (xy -0.925 0.47) (xy 0.925 0.47) (xy 0.925 -0.47)
			)
			(stroke
				(width 0.05)
				(type default)
			)
			(fill no)
			(layer "F.CrtYd")
		)
		(fp_poly
			(pts
				(xy -0.5 -0.25) (xy -0.5 0.25) (xy 0.5 0.25) (xy 0.5 -0.25)
			)
			(stroke
				(width 0.15)
				(type solid)
			)
			(fill no)
			(layer "F.Fab")
		)
		(fp_text user "${REFERENCE}"
			(at -0.95 3.168 0)
			(layer "F.Fab")
			(effects
				(font
					(size 0.7 0.7)
					(thickness 0.15)
				)
				(justify left bottom)
			)
		)
		(fp_text user "Author: Antmicro"
			(at -0.95 4.169 0)
			(layer "F.Fab")
			(effects
				(font
					(size 0.7 0.7)
					(thickness 0.15)
				)
				(justify left bottom)
			)
		)
		(fp_text user "License: Apache-2.0"
			(at -0.949999 5.169 0)
			(layer "F.Fab")
			(effects
				(font
					(size 0.7 0.7)
					(thickness 0.15)
				)
				(justify left bottom)
			)
		)
		(pad "1" smd roundrect
			(at -0.48 0)
			(size 0.59 0.64)
			(layers "F.Cu" "F.Mask" "F.Paste")
			(roundrect_rratio 0.25)
			(net 1306 "/DCDC/5V_{AON}_MODE1")
			(pintype "passive")
		)
		(pad "2" smd roundrect
			(at 0.48 0)
			(size 0.59 0.64)
			(layers "F.Cu" "F.Mask" "F.Paste")
			(roundrect_rratio 0.25)
			(net 1274 "/DCDC/5V_{AON}_VDD")
			(pintype "passive")
		)
	)
)
